# BASEBOARD_FAB2 (Tioga Pass) — schematic netlist excerpt (pin names and nets, part order shuffled) for the footprints in the layout excerpt that follows; sources: Cadence DE-HDL packaged netlist, KiCad conversion of Wiwynn_Tioga_Pass_MB.brd

R1W44  RES  4.75K 1% CHIP  pkg 0402  page 188 : A = P3V3_STBY ; B = FM_GBE2_LVC3_MOD_ABS
R5N5  RES  10.0K 1% CHIP  pkg 0402  page 21 : A = P3V3_STBY ; B = FM_CPU0_PKGID1

(kicad_pcb
	(version 20260206)
	(generator "pcbnew")
	(generator_version "10.0")
	(general
		(thickness 1.6)
		(legacy_teardrops no)
	)
	(paper "A4")
	(title_block
		(title "Wiwynn_Tioga_Pass_MB.brd")
		(comment 1 "Tioga Pass / footprints 4435-4437 of 4770")
	)
	(layers
		(0 "F.Cu" signal "TOP")
		(4 "In1.Cu" signal "L2GND")
		(6 "In2.Cu" signal "L3")
		(8 "In3.Cu" signal "L4GND")
		(10 "In4.Cu" signal "L5")
		(12 "In5.Cu" signal "L6GND")
		(14 "In6.Cu" signal "L7VCC")
		(16 "In7.Cu" signal "L8VCC")
		(18 "In8.Cu" signal "L9GND")
		(20 "In9.Cu" signal "L10")
		(22 "In10.Cu" signal "L11GND")
		(24 "In11.Cu" signal "L12")
		(26 "In12.Cu" signal "L13GND")
		(2 "B.Cu" signal "BOTTOM")
		(9 "F.Adhes" user "F.Adhesive")
		(11 "B.Adhes" user "B.Adhesive")
		(13 "F.Paste" user "Package Geometry/Pastemask Top")
		(15 "B.Paste" user "Package Geometry/Pastemask Bottom")
		(5 "F.SilkS" user "Ref Des/Silkscreen Top")
		(7 "B.SilkS" user "Ref Des/Silkscreen Bottom")
		(1 "F.Mask" user "Board Geometry/Soldermask Top")
		(3 "B.Mask" user "Board Geometry/Soldermask Bottom")
		(17 "Dwgs.User" user "User.Drawings")
		(19 "Cmts.User" user "User.Comments")
		(21 "Eco1.User" user "User.Eco1")
		(23 "Eco2.User" user "User.Eco2")
		(25 "Edge.Cuts" user "Board Geometry/Outline")
		(27 "Margin" user)
		(31 "F.CrtYd" user "Package Geometry/Place Bound Top")
		(29 "B.CrtYd" user "Package Geometry/Place Bound Bottom")
		(35 "F.Fab" user "Ref Des/Assembly Top")
		(33 "B.Fab" user "Ref Des/Assembly Bottom")
	)
	(footprint ""
		(layer "B.Cu")
		(at 470.027 -59.436 -90)
		(property "Reference" "R1W44"
			(at 0.8382 -0.67818 270)
			(unlocked yes)
			(layer "B.SilkS")
			(effects
				(font
					(size 0.4064 0.254)
					(thickness 0.1524)
				)
				(justify left mirror)
			)
		)
		(property "Value" ""
			(at 0 0 90)
			(layer "B.Fab")
			(effects
				(font
					(size 1.27 1.27)
				)
				(justify mirror)
			)
		)
		(duplicate_pad_numbers_are_jumpers no)
		(fp_poly
			(pts
				(xy 0.2794 -0.1016) (xy -0.2794 -0.1016) (xy -0.2794 0.9906) (xy 0.2794 0.9906)
			)
			(stroke
				(width 0)
				(type default)
			)
			(fill no)
			(layer "B.CrtYd")
		)
		(fp_line
			(start -0.2794 0.9906)
			(end -0.2794 -0.1016)
			(stroke
				(width 0.1)
				(type default)
			)
			(layer "B.Fab")
		)
		(fp_line
			(start 0.2794 0.9906)
			(end -0.2794 0.9906)
			(stroke
				(width 0.1)
				(type default)
			)
			(layer "B.Fab")
		)
		(fp_line
			(start -0.2794 -0.1016)
			(end 0.2794 -0.1016)
			(stroke
				(width 0.1)
				(type default)
			)
			(layer "B.Fab")
		)
		(fp_line
			(start 0.2794 -0.1016)
			(end 0.2794 0.9906)
			(stroke
				(width 0.1)
				(type default)
			)
			(layer "B.Fab")
		)
		(pad "1" smd rect
			(at 0 0 90)
			(size 0.508 0.508)
			(layers "B.Cu" "B.Mask" "B.Paste")
			(net "P3V3_STBY")
		)
		(pad "2" smd rect
			(at 0 0.889 90)
			(size 0.508 0.508)
			(layers "B.Cu" "B.Mask" "B.Paste")
			(net "FM_GBE2_LVC3_MOD_ABS")
		)
		(zone
			(layer "B.Cu")
			(hatch none 0.5)
			(connect_pads
				(clearance 0)
			)
			(min_thickness 0.25)
			(keepout
				(tracks not_allowed)
				(vias allowed)
				(pads allowed)
				(copperpour not_allowed)
				(footprints allowed)
			)
			(placement
				(enabled no)
				(sheetname "")
			)
			(fill
				(thermal_gap 0.5)
				(thermal_bridge_width 0.5)
				(island_removal_mode 0)
			)
			(polygon
				(pts
					(xy 469.392 -59.182) (xy 469.392 -59.69) (xy 469.773 -59.69) (xy 469.773 -59.182)
				)
			)
		)
		(zone
			(layer "B.Cu")
			(hatch none 0.5)
			(connect_pads
				(clearance 0)
			)
			(min_thickness 0.25)
			(keepout
				(tracks allowed)
				(vias not_allowed)
				(pads allowed)
				(copperpour not_allowed)
				(footprints allowed)
			)
			(placement
				(enabled no)
				(sheetname "")
			)
			(fill
				(thermal_gap 0.5)
				(thermal_bridge_width 0.5)
				(island_removal_mode 0)
			)
			(polygon
				(pts
					(xy 469.773 -59.182) (xy 469.773 -59.69) (xy 469.392 -59.69) (xy 469.392 -59.182)
				)
			)
		)
	)
	(footprint ""
		(layer "B.Cu")
		(at 120.65 -31.115)
		(property "Reference" ""
			(at 0 0 0)
			(layer "B.SilkS")
			(hide yes)
			(effects
				(font
					(size 1.27 1.27)
				)
				(justify mirror)
			)
		)
		(property "Value" ""
			(at 0 0 0)
			(layer "B.Fab")
			(effects
				(font
					(size 1.27 1.27)
				)
				(justify mirror)
			)
		)
		(duplicate_pad_numbers_are_jumpers no)
		(fp_poly
			(pts
				(arc
					(start 2.032 0)
					(mid -2.032 0)
					(end 2.032 0)
				)
			)
			(stroke
				(width 0)
				(type default)
			)
			(fill no)
			(layer "B.CrtYd")
		)
		(pad "1" smd circle
			(at 0 0 180)
			(size 1.016 1.016)
			(layers "B.Cu" "B.Mask" "B.Paste")
			(net "Net_388")
		)
		(zone
			(layers "F.Cu" "B.Cu" "In1.Cu" "In2.Cu" "In3.Cu" "In4.Cu" "In5.Cu" "In6.Cu"
				"In7.Cu" "In8.Cu" "In9.Cu" "In10.Cu" "In11.Cu" "In12.Cu"
			)
			(hatch none 0.5)
			(connect_pads
				(clearance 0)
			)
			(min_thickness 0.25)
			(keepout
				(tracks allowed)
				(vias not_allowed)
				(pads allowed)
				(copperpour not_allowed)
				(footprints allowed)
			)
			(placement
				(enabled no)
				(sheetname "")
			)
			(fill
				(thermal_gap 0.5)
				(thermal_bridge_width 0.5)
				(island_removal_mode 0)
			)
			(polygon
				(pts
					(arc
						(start 122.174 -31.115)
						(mid 119.126 -31.115)
						(end 122.174 -31.115)
					)
				)
			)
		)
		(zone
			(layer "B.Cu")
			(hatch none 0.5)
			(connect_pads
				(clearance 0)
			)
			(min_thickness 0.25)
			(keepout
				(tracks not_allowed)
				(vias allowed)
				(pads allowed)
				(copperpour not_allowed)
				(footprints allowed)
			)
			(placement
				(enabled no)
				(sheetname "")
			)
			(fill
				(thermal_gap 0.5)
				(thermal_bridge_width 0.5)
				(island_removal_mode 0)
			)
			(polygon
				(pts
					(arc
						(start 122.174 -31.115)
						(mid 119.126 -31.115)
						(end 122.174 -31.115)
					)
				)
			)
		)
	)
	(footprint ""
		(layer "B.Cu")
		(at 227.584 -90.297 90)
		(property "Reference" "R5N5"
			(at 0 0 90)
			(layer "B.SilkS")
			(hide yes)
			(effects
				(font
					(size 1.27 1.27)
				)
				(justify mirror)
			)
		)
		(property "Value" ""
			(at 0 0 90)
			(layer "B.Fab")
			(effects
				(font
					(size 1.27 1.27)
				)
				(justify mirror)
			)
		)
		(duplicate_pad_numbers_are_jumpers no)
		(fp_poly
			(pts
				(xy 0.2794 -0.1016) (xy -0.2794 -0.1016) (xy -0.2794 0.9906) (xy 0.2794 0.9906)
			)
			(stroke
				(width 0)
				(type default)
			)
			(fill no)
			(layer "B.CrtYd")
		)
		(fp_line
			(start 0.2794 -0.1016)
			(end 0.2794 0.9906)
			(stroke
				(width 0.1)
				(type default)
			)
			(layer "B.Fab")
		)
		(fp_line
			(start -0.2794 -0.1016)
			(end 0.2794 -0.1016)
			(stroke
				(width 0.1)
				(type default)
			)
			(layer "B.Fab")
		)
		(fp_line
			(start 0.2794 0.9906)
			(end -0.2794 0.9906)
			(stroke
				(width 0.1)
				(type default)
			)
			(layer "B.Fab")
		)
		(fp_line
			(start -0.2794 0.9906)
			(end -0.2794 -0.1016)
			(stroke
				(width 0.1)
				(type default)
			)
			(layer "B.Fab")
		)
		(pad "1" smd rect
			(at 0 0 270)
			(size 0.508 0.508)
			(layers "B.Cu" "B.Mask" "B.Paste")
			(net "P3V3_STBY")
		)
		(pad "2" smd rect
			(at 0 0.889 270)
			(size 0.508 0.508)
			(layers "B.Cu" "B.Mask" "B.Paste")
			(net "FM_CPU0_PKGID1")
		)
		(zone
			(layer "B.Cu")
			(hatch none 0.5)
			(connect_pads
				(clearance 0)
			)
			(min_thickness 0.25)
			(keepout
				(tracks allowed)
				(vias not_allowed)
				(pads allowed)
				(copperpour not_allowed)
				(footprints allowed)
			)
			(placement
				(enabled no)
				(sheetname "")
			)
			(fill
				(thermal_gap 0.5)
				(thermal_bridge_width 0.5)
				(island_removal_mode 0)
			)
			(polygon
				(pts
					(xy 227.838 -90.551) (xy 227.838 -90.043) (xy 228.219 -90.043) (xy 228.219 -90.551)
				)
			)
		)
		(zone
			(layer "B.Cu")
			(hatch none 0.5)
			(connect_pads
				(clearance 0)
			)
			(min_thickness 0.25)
			(keepout
				(tracks not_allowed)
				(vias allowed)
				(pads allowed)
				(copperpour not_allowed)
				(footprints allowed)
			)
			(placement
				(enabled no)
				(sheetname "")
			)
			(fill
				(thermal_gap 0.5)
				(thermal_bridge_width 0.5)
				(island_removal_mode 0)
			)
			(polygon
				(pts
					(xy 228.219 -90.551) (xy 228.219 -90.043) (xy 227.838 -90.043) (xy 227.838 -90.551)
				)
			)
		)
	)
)
